(kicad_pcb
	(version 20260206)
	(generator "pcbnew")
	(generator_version "10.0")
	(general
		(thickness 1.6)
		(legacy_teardrops no)
	)
	(paper "A4")
	(title_block
		(title "9054_F0T_PDB_BD_GPU_F_V04_1213_1550_OCP.brd")
		(comment 1 "Grand Teton / footprints 489-495 of 608")
	)
	(layers
		(0 "F.Cu" signal "TOP")
		(4 "In1.Cu" signal "GND")
		(6 "In2.Cu" signal "IN1")
		(8 "In3.Cu" signal "GND1")
		(10 "In4.Cu" signal "VCC")
		(12 "In5.Cu" signal "VCC1")
		(14 "In6.Cu" signal "GND2")
		(16 "In7.Cu" signal "IN2")
		(18 "In8.Cu" signal "GND3")
		(2 "B.Cu" signal "BOTTOM")
		(9 "F.Adhes" user "F.Adhesive")
		(11 "B.Adhes" user "B.Adhesive")
		(13 "F.Paste" user "Package Geometry/Pastemask Top")
		(15 "B.Paste" user "Package Geometry/Pastemask Bottom")
		(5 "F.SilkS" user "Ref Des/Silkscreen Top")
		(7 "B.SilkS" user "Ref Des/Silkscreen Bottom")
		(1 "F.Mask" user "Board Geometry/Soldermask Top")
		(3 "B.Mask" user "Board Geometry/Soldermask Bottom")
		(17 "Dwgs.User" user "User.Drawings")
		(19 "Cmts.User" user "User.Comments")
		(21 "Eco1.User" user "User.Eco1")
		(23 "Eco2.User" user "User.Eco2")
		(25 "Edge.Cuts" user "Board Geometry/Outline")
		(27 "Margin" user)
		(31 "F.CrtYd" user "Package Geometry/Place Bound Top")
		(29 "B.CrtYd" user "Package Geometry/Place Bound Bottom")
		(35 "F.Fab" user "Ref Des/Assembly Top")
		(33 "B.Fab" user "Ref Des/Assembly Bottom")
	)
	(footprint ""
		(layer "B.Cu")
		(at 176.195736 -63.754 180)
		(property "Reference" "PC609"
			(at 0 0 0)
			(layer "B.SilkS")
			(hide yes)
			(effects
				(font
					(size 1.27 1.27)
				)
				(justify mirror)
			)
		)
		(property "Value" ""
			(at 0 0 0)
			(layer "B.Fab")
			(effects
				(font
					(size 1.27 1.27)
				)
				(justify mirror)
			)
		)
		(duplicate_pad_numbers_are_jumpers no)
		(fp_line
			(start 0.7874 0.4064)
			(end 0.7874 -0.4064)
			(stroke
				(width 0.1524)
				(type default)
			)
			(layer "B.SilkS")
		)
		(fp_line
			(start 0.7874 -0.4064)
			(end -0.7874 -0.4064)
			(stroke
				(width 0.1524)
				(type default)
			)
			(layer "B.SilkS")
		)
		(fp_line
			(start -0.7874 0.4064)
			(end 0.7874 0.4064)
			(stroke
				(width 0.1524)
				(type default)
			)
			(layer "B.SilkS")
		)
		(fp_line
			(start -0.7874 -0.4064)
			(end -0.7874 0.4064)
			(stroke
				(width 0.1524)
				(type default)
			)
			(layer "B.SilkS")
		)
		(fp_line
			(start 0.67945 0.3048)
			(end 0.67945 -0.305054)
			(stroke
				(width 0.1)
				(type default)
			)
			(layer "B.Fab")
		)
		(fp_line
			(start 0.67945 -0.305054)
			(end 0.12065 -0.305054)
			(stroke
				(width 0.1)
				(type default)
			)
			(layer "B.Fab")
		)
		(fp_line
			(start 0.12065 0.3048)
			(end 0.67945 0.3048)
			(stroke
				(width 0.1)
				(type default)
			)
			(layer "B.Fab")
		)
		(fp_line
			(start 0.12065 0.2794)
			(end 0.12065 0.3048)
			(stroke
				(width 0.1)
				(type default)
			)
			(layer "B.Fab")
		)
		(fp_line
			(start 0.12065 -0.2794)
			(end -0.12065 -0.2794)
			(stroke
				(width 0.1)
				(type default)
			)
			(layer "B.Fab")
		)
		(fp_line
			(start 0.12065 -0.305054)
			(end 0.12065 -0.2794)
			(stroke
				(width 0.1)
				(type default)
			)
			(layer "B.Fab")
		)
		(fp_line
			(start -0.120396 0.3048)
			(end -0.120396 0.2794)
			(stroke
				(width 0.1)
				(type default)
			)
			(layer "B.Fab")
		)
		(fp_line
			(start -0.120396 0.2794)
			(end 0.12065 0.2794)
			(stroke
				(width 0.1)
				(type default)
			)
			(layer "B.Fab")
		)
		(fp_line
			(start -0.12065 -0.2794)
			(end -0.12065 -0.3048)
			(stroke
				(width 0.1)
				(type default)
			)
			(layer "B.Fab")
		)
		(fp_line
			(start -0.12065 -0.3048)
			(end -0.67945 -0.3048)
			(stroke
				(width 0.1)
				(type default)
			)
			(layer "B.Fab")
		)
		(fp_line
			(start -0.67945 0.3048)
			(end -0.120396 0.3048)
			(stroke
				(width 0.1)
				(type default)
			)
			(layer "B.Fab")
		)
		(fp_line
			(start -0.67945 -0.3048)
			(end -0.67945 0.3048)
			(stroke
				(width 0.1)
				(type default)
			)
			(layer "B.Fab")
		)
		(pad "1" smd circle
			(at 0.40005 0)
			(size 0 0)
			(layers "B.Cu" "B.Mask" "B.Paste")
			(net "P52V_HS2_TEMPP")
		)
		(pad "2" smd circle
			(at -0.40005 0)
			(size 0 0)
			(layers "B.Cu" "B.Mask" "B.Paste")
			(net "P52V_HS2_TEMPN")
		)
	)
	(footprint ""
		(layer "B.Cu")
		(at 185.212736 -71.12 -90)
		(property "Reference" "PC608"
			(at 0 0 90)
			(layer "B.SilkS")
			(hide yes)
			(effects
				(font
					(size 1.27 1.27)
				)
				(justify mirror)
			)
		)
		(property "Value" ""
			(at 0 0 90)
			(layer "B.Fab")
			(effects
				(font
					(size 1.27 1.27)
				)
				(justify mirror)
			)
		)
		(duplicate_pad_numbers_are_jumpers no)
		(fp_line
			(start -2.2098 0.9398)
			(end 2.2098 0.9398)
			(stroke
				(width 0.1524)
				(type default)
			)
			(layer "B.SilkS")
		)
		(fp_line
			(start 2.2098 0.9398)
			(end 2.2098 -0.9398)
			(stroke
				(width 0.1524)
				(type default)
			)
			(layer "B.SilkS")
		)
		(fp_line
			(start -2.2098 -0.9398)
			(end -2.2098 0.9398)
			(stroke
				(width 0.1524)
				(type default)
			)
			(layer "B.SilkS")
		)
		(fp_line
			(start 2.2098 -0.9398)
			(end -2.2098 -0.9398)
			(stroke
				(width 0.1524)
				(type default)
			)
			(layer "B.SilkS")
		)
		(fp_line
			(start -1.6764 0.9398)
			(end 1.6764 0.9398)
			(stroke
				(width 0.1)
				(type default)
			)
			(layer "B.Fab")
		)
		(fp_line
			(start 1.6764 0.9398)
			(end 1.6764 0.889)
			(stroke
				(width 0.1)
				(type default)
			)
			(layer "B.Fab")
		)
		(fp_line
			(start -1.6764 0.889)
			(end -1.6764 0.9398)
			(stroke
				(width 0.1)
				(type default)
			)
			(layer "B.Fab")
		)
		(fp_line
			(start 1.6764 0.889)
			(end 1.6764 0.8382)
			(stroke
				(width 0.1)
				(type default)
			)
			(layer "B.Fab")
		)
		(fp_line
			(start -2.1082 0.8382)
			(end -1.6764 0.8382)
			(stroke
				(width 0.1)
				(type default)
			)
			(layer "B.Fab")
		)
		(fp_line
			(start -1.6764 0.8382)
			(end -1.6764 0.889)
			(stroke
				(width 0.1)
				(type default)
			)
			(layer "B.Fab")
		)
		(fp_line
			(start 1.6764 0.8382)
			(end 2.1082 0.8382)
			(stroke
				(width 0.1)
				(type default)
			)
			(layer "B.Fab")
		)
		(fp_line
			(start 2.1082 0.8382)
			(end 2.1082 -0.8382)
			(stroke
				(width 0.1)
				(type default)
			)
			(layer "B.Fab")
		)
		(fp_line
			(start -2.1082 -0.8382)
			(end -2.1082 0.8382)
			(stroke
				(width 0.1)
				(type default)
			)
			(layer "B.Fab")
		)
		(fp_line
			(start -1.6764 -0.8382)
			(end -2.1082 -0.8382)
			(stroke
				(width 0.1)
				(type default)
			)
			(layer "B.Fab")
		)
		(fp_line
			(start 1.6764 -0.8382)
			(end 1.6764 -0.889)
			(stroke
				(width 0.1)
				(type default)
			)
			(layer "B.Fab")
		)
		(fp_line
			(start 2.1082 -0.8382)
			(end 1.6764 -0.8382)
			(stroke
				(width 0.1)
				(type default)
			)
			(layer "B.Fab")
		)
		(fp_line
			(start -1.6764 -0.889)
			(end -1.6764 -0.8382)
			(stroke
				(width 0.1)
				(type default)
			)
			(layer "B.Fab")
		)
		(fp_line
			(start 1.6764 -0.889)
			(end 1.6764 -0.9398)
			(stroke
				(width 0.1)
				(type default)
			)
			(layer "B.Fab")
		)
		(fp_line
			(start -1.6764 -0.9398)
			(end -1.6764 -0.889)
			(stroke
				(width 0.1)
				(type default)
			)
			(layer "B.Fab")
		)
		(fp_line
			(start 1.6764 -0.9398)
			(end -1.6764 -0.9398)
			(stroke
				(width 0.1)
				(type default)
			)
			(layer "B.Fab")
		)
		(pad "1" smd rect
			(at 1.4732 0 270)
			(size 1.1684 1.5748)
			(layers "B.Cu" "B.Mask" "B.Paste")
			(net "P52V_HS2")
		)
		(pad "2" smd rect
			(at -1.4732 0 270)
			(size 1.1684 1.5748)
			(layers "B.Cu" "B.Mask" "B.Paste")
			(net "P52V_HS2_VCP")
		)
	)
	(footprint ""
		(layer "B.Cu")
		(at 174.798736 -63.754 90)
		(property "Reference" "PR7021"
			(at 0 0 90)
			(layer "B.SilkS")
			(hide yes)
			(effects
				(font
					(size 1.27 1.27)
				)
				(justify mirror)
			)
		)
		(property "Value" ""
			(at 0 0 90)
			(layer "B.Fab")
			(effects
				(font
					(size 1.27 1.27)
				)
				(justify mirror)
			)
		)
		(duplicate_pad_numbers_are_jumpers no)
		(fp_line
			(start 0.7874 -0.4064)
			(end -0.7874 -0.4064)
			(stroke
				(width 0.1524)
				(type default)
			)
			(layer "B.SilkS")
		)
		(fp_line
			(start -0.7874 -0.4064)
			(end -0.7874 0.4064)
			(stroke
				(width 0.1524)
				(type default)
			)
			(layer "B.SilkS")
		)
		(fp_line
			(start 0.7874 0.4064)
			(end 0.7874 -0.4064)
			(stroke
				(width 0.1524)
				(type default)
			)
			(layer "B.SilkS")
		)
		(fp_line
			(start -0.7874 0.4064)
			(end 0.7874 0.4064)
			(stroke
				(width 0.1524)
				(type default)
			)
			(layer "B.SilkS")
		)
		(fp_line
			(start 0.67945 -0.305054)
			(end 0.12065 -0.305054)
			(stroke
				(width 0.1)
				(type default)
			)
			(layer "B.Fab")
		)
		(fp_line
			(start 0.12065 -0.305054)
			(end 0.12065 -0.2794)
			(stroke
				(width 0.1)
				(type default)
			)
			(layer "B.Fab")
		)
		(fp_line
			(start -0.12065 -0.3048)
			(end -0.67945 -0.3048)
			(stroke
				(width 0.1)
				(type default)
			)
			(layer "B.Fab")
		)
		(fp_line
			(start -0.67945 -0.3048)
			(end -0.67945 0.3048)
			(stroke
				(width 0.1)
				(type default)
			)
			(layer "B.Fab")
		)
		(fp_line
			(start 0.12065 -0.2794)
			(end -0.12065 -0.2794)
			(stroke
				(width 0.1)
				(type default)
			)
			(layer "B.Fab")
		)
		(fp_line
			(start -0.12065 -0.2794)
			(end -0.12065 -0.3048)
			(stroke
				(width 0.1)
				(type default)
			)
			(layer "B.Fab")
		)
		(fp_line
			(start 0.12065 0.2794)
			(end 0.12065 0.3048)
			(stroke
				(width 0.1)
				(type default)
			)
			(layer "B.Fab")
		)
		(fp_line
			(start -0.120396 0.2794)
			(end 0.12065 0.2794)
			(stroke
				(width 0.1)
				(type default)
			)
			(layer "B.Fab")
		)
		(fp_line
			(start 0.67945 0.3048)
			(end 0.67945 -0.305054)
			(stroke
				(width 0.1)
				(type default)
			)
			(layer "B.Fab")
		)
		(fp_line
			(start 0.12065 0.3048)
			(end 0.67945 0.3048)
			(stroke
				(width 0.1)
				(type default)
			)
			(layer "B.Fab")
		)
		(fp_line
			(start -0.120396 0.3048)
			(end -0.120396 0.2794)
			(stroke
				(width 0.1)
				(type default)
			)
			(layer "B.Fab")
		)
		(fp_line
			(start -0.67945 0.3048)
			(end -0.120396 0.3048)
			(stroke
				(width 0.1)
				(type default)
			)
			(layer "B.Fab")
		)
		(pad "1" smd circle
			(at 0.40005 0 270)
			(size 0 0)
			(layers "B.Cu" "B.Mask" "B.Paste")
			(net "P52V_HS2_UVH")
		)
		(pad "2" smd circle
			(at -0.40005 0 270)
			(size 0 0)
			(layers "B.Cu" "B.Mask" "B.Paste")
			(net "GND1_FIELD_SIGNAL")
		)
	)
	(footprint ""
		(layer "B.Cu")
		(at 273.812 -91.567 180)
		(property "Reference" "R5902"
			(at 0 0 0)
			(layer "B.SilkS")
			(hide yes)
			(effects
				(font
					(size 1.27 1.27)
				)
				(justify mirror)
			)
		)
		(property "Value" ""
			(at 0 0 0)
			(layer "B.Fab")
			(effects
				(font
					(size 1.27 1.27)
				)
				(justify mirror)
			)
		)
		(duplicate_pad_numbers_are_jumpers no)
		(fp_line
			(start 1.651 0.8382)
			(end 1.651 -0.8382)
			(stroke
				(width 0.1524)
				(type default)
			)
			(layer "B.SilkS")
		)
		(fp_line
			(start 1.651 -0.8382)
			(end -1.651 -0.8382)
			(stroke
				(width 0.1524)
				(type default)
			)
			(layer "B.SilkS")
		)
		(fp_line
			(start -1.651 0.8382)
			(end 1.651 0.8382)
			(stroke
				(width 0.1524)
				(type default)
			)
			(layer "B.SilkS")
		)
		(fp_line
			(start -1.651 -0.8382)
			(end -1.651 0.8382)
			(stroke
				(width 0.1524)
				(type default)
			)
			(layer "B.SilkS")
		)
		(fp_line
			(start 1.559814 0.7366)
			(end 1.524 0.7366)
			(stroke
				(width 0.1)
				(type default)
			)
			(layer "B.Fab")
		)
		(fp_line
			(start 1.559814 -0.7366)
			(end 1.559814 0.7366)
			(stroke
				(width 0.1)
				(type default)
			)
			(layer "B.Fab")
		)
		(fp_line
			(start 1.524 0.7366)
			(end -1.524 0.7366)
			(stroke
				(width 0.1)
				(type default)
			)
			(layer "B.Fab")
		)
		(fp_line
			(start 1.524 -0.7366)
			(end 1.559814 -0.7366)
			(stroke
				(width 0.1)
				(type default)
			)
			(layer "B.Fab")
		)
		(fp_line
			(start -1.524 0.7366)
			(end -1.560576 0.7366)
			(stroke
				(width 0.1)
				(type default)
			)
			(layer "B.Fab")
		)
		(fp_line
			(start -1.524 -0.7366)
			(end 1.524 -0.7366)
			(stroke
				(width 0.1)
				(type default)
			)
			(layer "B.Fab")
		)
		(fp_line
			(start -1.560576 0.7366)
			(end -1.560576 -0.7366)
			(stroke
				(width 0.1)
				(type default)
			)
			(layer "B.Fab")
		)
		(fp_line
			(start -1.560576 -0.7366)
			(end -1.524 -0.7366)
			(stroke
				(width 0.1)
				(type default)
			)
			(layer "B.Fab")
		)
		(pad "1" smd rect
			(at 0.94996 0 180)
			(size 1.1176 1.3716)
			(layers "B.Cu" "B.Mask" "B.Paste")
			(net "P52V_1_BUSBAR")
		)
		(pad "2" smd rect
			(at -0.94996 0 180)
			(size 1.1176 1.3716)
			(layers "B.Cu" "B.Mask" "B.Paste")
			(net "FM_HS1_EN_BUSBAR")
		)
	)
	(footprint ""
		(layer "B.Cu")
		(at 167.940736 -59.309 180)
		(property "Reference" "PR7024"
			(at 0 0 0)
			(layer "B.SilkS")
			(hide yes)
			(effects
				(font
					(size 1.27 1.27)
				)
				(justify mirror)
			)
		)
		(property "Value" ""
			(at 0 0 0)
			(layer "B.Fab")
			(effects
				(font
					(size 1.27 1.27)
				)
				(justify mirror)
			)
		)
		(duplicate_pad_numbers_are_jumpers no)
		(fp_line
			(start 1.651 0.8382)
			(end 1.651 -0.8382)
			(stroke
				(width 0.1524)
				(type default)
			)
			(layer "B.SilkS")
		)
		(fp_line
			(start 1.651 -0.8382)
			(end -1.651 -0.8382)
			(stroke
				(width 0.1524)
				(type default)
			)
			(layer "B.SilkS")
		)
		(fp_line
			(start -1.651 0.8382)
			(end 1.651 0.8382)
			(stroke
				(width 0.1524)
				(type default)
			)
			(layer "B.SilkS")
		)
		(fp_line
			(start -1.651 -0.8382)
			(end -1.651 0.8382)
			(stroke
				(width 0.1524)
				(type default)
			)
			(layer "B.SilkS")
		)
		(fp_line
			(start 1.559814 0.7366)
			(end 1.524 0.7366)
			(stroke
				(width 0.1)
				(type default)
			)
			(layer "B.Fab")
		)
		(fp_line
			(start 1.559814 -0.7366)
			(end 1.559814 0.7366)
			(stroke
				(width 0.1)
				(type default)
			)
			(layer "B.Fab")
		)
		(fp_line
			(start 1.524 0.7366)
			(end -1.524 0.7366)
			(stroke
				(width 0.1)
				(type default)
			)
			(layer "B.Fab")
		)
		(fp_line
			(start 1.524 -0.7366)
			(end 1.559814 -0.7366)
			(stroke
				(width 0.1)
				(type default)
			)
			(layer "B.Fab")
		)
		(fp_line
			(start -1.524 0.7366)
			(end -1.560576 0.7366)
			(stroke
				(width 0.1)
				(type default)
			)
			(layer "B.Fab")
		)
		(fp_line
			(start -1.524 -0.7366)
			(end 1.524 -0.7366)
			(stroke
				(width 0.1)
				(type default)
			)
			(layer "B.Fab")
		)
		(fp_line
			(start -1.560576 0.7366)
			(end -1.560576 -0.7366)
			(stroke
				(width 0.1)
				(type default)
			)
			(layer "B.Fab")
		)
		(fp_line
			(start -1.560576 -0.7366)
			(end -1.524 -0.7366)
			(stroke
				(width 0.1)
				(type default)
			)
			(layer "B.Fab")
		)
		(pad "1" smd rect
			(at 0.94996 0 180)
			(size 1.1176 1.3716)
			(layers "B.Cu" "B.Mask" "B.Paste")
			(net "P52V_HS2")
		)
		(pad "2" smd rect
			(at -0.94996 0 180)
			(size 1.1176 1.3716)
			(layers "B.Cu" "B.Mask" "B.Paste")
			(net "P52V_HS2_ISET")
		)
	)
	(footprint ""
		(layer "B.Cu")
		(at 180.259736 -77.47)
		(property "Reference" "PC616"
			(at 0 0 0)
			(layer "B.SilkS")
			(hide yes)
			(effects
				(font
					(size 1.27 1.27)
				)
				(justify mirror)
			)
		)
		(property "Value" ""
			(at 0 0 0)
			(layer "B.Fab")
			(effects
				(font
					(size 1.27 1.27)
				)
				(justify mirror)
			)
		)
		(duplicate_pad_numbers_are_jumpers no)
		(fp_line
			(start -1.524 -0.762)
			(end -1.524 0.762)
			(stroke
				(width 0.1524)
				(type default)
			)
			(layer "B.SilkS")
		)
		(fp_line
			(start -1.524 0.762)
			(end 1.524 0.762)
			(stroke
				(width 0.1524)
				(type default)
			)
			(layer "B.SilkS")
		)
		(fp_line
			(start 1.524 -0.762)
			(end -1.524 -0.762)
			(stroke
				(width 0.1524)
				(type default)
			)
			(layer "B.SilkS")
		)
		(fp_line
			(start 1.524 0.762)
			(end 1.524 -0.762)
			(stroke
				(width 0.1524)
				(type default)
			)
			(layer "B.SilkS")
		)
		(fp_line
			(start -1.1049 -0.724916)
			(end 1.1049 -0.724916)
			(stroke
				(width 0.1)
				(type default)
			)
			(layer "B.Fab")
		)
		(fp_line
			(start -1.1049 0.724916)
			(end -1.1049 -0.724916)
			(stroke
				(width 0.1)
				(type default)
			)
			(layer "B.Fab")
		)
		(fp_line
			(start 1.1049 -0.724916)
			(end 1.1049 0.724916)
			(stroke
				(width 0.1)
				(type default)
			)
			(layer "B.Fab")
		)
		(fp_line
			(start 1.1049 0.724916)
			(end -1.1049 0.724916)
			(stroke
				(width 0.1)
				(type default)
			)
			(layer "B.Fab")
		)
		(pad "1" smd rect
			(at 0.889 0)
			(size 1.016 1.27)
			(layers "B.Cu" "B.Mask" "B.Paste")
			(net "P52V_HS2_DV_DT")
		)
		(pad "2" smd rect
			(at -0.889 0)
			(size 1.016 1.27)
			(layers "B.Cu" "B.Mask" "B.Paste")
			(net "GND1_FIELD_SIGNAL")
		)
	)
	(footprint ""
		(layer "B.Cu")
		(at 177.719736 -63.754 90)
		(property "Reference" "PC613"
			(at 0 0 90)
			(layer "B.SilkS")
			(hide yes)
			(effects
				(font
					(size 1.27 1.27)
				)
				(justify mirror)
			)
		)
		(property "Value" ""
			(at 0 0 90)
			(layer "B.Fab")
			(effects
				(font
					(size 1.27 1.27)
				)
				(justify mirror)
			)
		)
		(duplicate_pad_numbers_are_jumpers no)
		(fp_line
			(start 0.7874 -0.4064)
			(end -0.7874 -0.4064)
			(stroke
				(width 0.1524)
				(type default)
			)
			(layer "B.SilkS")
		)
		(fp_line
			(start -0.7874 -0.4064)
			(end -0.7874 0.4064)
			(stroke
				(width 0.1524)
				(type default)
			)
			(layer "B.SilkS")
		)
		(fp_line
			(start 0.7874 0.4064)
			(end 0.7874 -0.4064)
			(stroke
				(width 0.1524)
				(type default)
			)
			(layer "B.SilkS")
		)
		(fp_line
			(start -0.7874 0.4064)
			(end 0.7874 0.4064)
			(stroke
				(width 0.1524)
				(type default)
			)
			(layer "B.SilkS")
		)
		(fp_line
			(start 0.67945 -0.305054)
			(end 0.12065 -0.305054)
			(stroke
				(width 0.1)
				(type default)
			)
			(layer "B.Fab")
		)
		(fp_line
			(start 0.12065 -0.305054)
			(end 0.12065 -0.2794)
			(stroke
				(width 0.1)
				(type default)
			)
			(layer "B.Fab")
		)
		(fp_line
			(start -0.12065 -0.3048)
			(end -0.67945 -0.3048)
			(stroke
				(width 0.1)
				(type default)
			)
			(layer "B.Fab")
		)
		(fp_line
			(start -0.67945 -0.3048)
			(end -0.67945 0.3048)
			(stroke
				(width 0.1)
				(type default)
			)
			(layer "B.Fab")
		)
		(fp_line
			(start 0.12065 -0.2794)
			(end -0.12065 -0.2794)
			(stroke
				(width 0.1)
				(type default)
			)
			(layer "B.Fab")
		)
		(fp_line
			(start -0.12065 -0.2794)
			(end -0.12065 -0.3048)
			(stroke
				(width 0.1)
				(type default)
			)
			(layer "B.Fab")
		)
		(fp_line
			(start 0.12065 0.2794)
			(end 0.12065 0.3048)
			(stroke
				(width 0.1)
				(type default)
			)
			(layer "B.Fab")
		)
		(fp_line
			(start -0.120396 0.2794)
			(end 0.12065 0.2794)
			(stroke
				(width 0.1)
				(type default)
			)
			(layer "B.Fab")
		)
		(fp_line
			(start 0.67945 0.3048)
			(end 0.67945 -0.305054)
			(stroke
				(width 0.1)
				(type default)
			)
			(layer "B.Fab")
		)
		(fp_line
			(start 0.12065 0.3048)
			(end 0.67945 0.3048)
			(stroke
				(width 0.1)
				(type default)
			)
			(layer "B.Fab")
		)
		(fp_line
			(start -0.120396 0.3048)
			(end -0.120396 0.2794)
			(stroke
				(width 0.1)
				(type default)
			)
			(layer "B.Fab")
		)
		(fp_line
			(start -0.67945 0.3048)
			(end -0.120396 0.3048)
			(stroke
				(width 0.1)
				(type default)
			)
			(layer "B.Fab")
		)
		(pad "1" smd circle
			(at 0.40005 0 270)
			(size 0 0)
			(layers "B.Cu" "B.Mask" "B.Paste")
			(net "P52V_HS2_VREG")
		)
		(pad "2" smd circle
			(at -0.40005 0 270)
			(size 0 0)
			(layers "B.Cu" "B.Mask" "B.Paste")
			(net "GND1_FIELD_SIGNAL")
		)
	)
)
